(kicad_pcb
	(version 20221018)
	(generator pcbnew)
	(general
    (thickness 1.7403)
  )
	(paper "A4")
	(title_block
    (title "Data Center RDIMM DDR4 Tester")
    (date "2024-09-30")
    (rev "1.2.4")
		(comment 9 "footprints 514-523 of 690")
	)
	(layers
    (0 "F.Cu" signal)
    (1 "In1.Cu" power)
    (2 "In2.Cu" signal)
    (3 "In3.Cu" power)
    (4 "In4.Cu" power)
    (5 "In5.Cu" signal)
    (6 "In6.Cu" power)
    (7 "In7.Cu" signal)
    (8 "In8.Cu" power)
    (9 "In9.Cu" signal)
    (10 "In10.Cu" power)
    (31 "B.Cu" signal)
    (32 "B.Adhes" user "B.Adhesive")
    (33 "F.Adhes" user "F.Adhesive")
    (34 "B.Paste" user)
    (35 "F.Paste" user)
    (36 "B.SilkS" user "B.Silkscreen")
    (37 "F.SilkS" user "F.Silkscreen")
    (38 "B.Mask" user)
    (39 "F.Mask" user)
    (40 "Dwgs.User" user "User.Drawings")
    (41 "Cmts.User" user "User.Comments")
    (42 "Eco1.User" user "User.Eco1")
    (43 "Eco2.User" user "User.Eco2")
    (44 "Edge.Cuts" user)
    (45 "Margin" user)
    (46 "B.CrtYd" user "B.Courtyard")
    (47 "F.CrtYd" user "F.Courtyard")
    (48 "B.Fab" user)
    (49 "F.Fab" user)
  )
	(footprint "data-center-rdimm-ddr4-tester-footprints:C_0402_1005Metric" (layer "B.Cu")
    (at 171.836328 59.660008 -90)
    (descr "Capacitor SMD 0402")
    (tags "capacitor SMD 0402")
    (property "Author" "Antmicro")
    (property "Dielectric" "X5R")
    (property "License" "Apache-2.0")
    (property "MPN" "GRM155R61H104KE14D")
    (property "Manufacturer" "Murata")
    (property "Sheetfile" "DDR4.kicad_sch")
    (property "Sheetname" "DDR4")
    (property "Val" "100n")
    (property "Voltage" "50V")
    (property "ki_description" " ")
    (attr smd)
    (fp_text reference "C179" (at 0.809992 -0.363672 90) (layer "B.SilkS")
        (effects (font (size 0.7 0.7) (thickness 0.15)) (justify left bottom mirror))
    )
    (fp_text value "C_100n_0402" (at 0 -1.4 90) (layer "B.Fab") hide
        (effects (font (size 0.7 0.7) (thickness 0.15)) (justify left bottom mirror))
    )
    (fp_text user "License: Apache-2.0" (at -0.932 -5.17 90) (layer "B.Fab") hide
        (effects (font (size 0.7 0.7) (thickness 0.15)) (justify left bottom mirror))
    )
    (fp_text user "Author: Antmicro" (at -0.932 -4.17 90) (layer "B.Fab") hide
        (effects (font (size 0.7 0.7) (thickness 0.15)) (justify left bottom mirror))
    )
    (fp_text user "${REFERENCE}" (at -0.932 -3.168 90) (layer "B.Fab") hide
        (effects (font (size 0.7 0.7) (thickness 0.15)) (justify left bottom mirror))
    )
    (fp_rect (start -0.94 0.47) (end 0.94 -0.47)
      (stroke (width 0.05) (type solid)) (fill none) (layer "B.CrtYd"))
    (fp_rect (start -0.499 0.249) (end 0.499 -0.249)
      (stroke (width 0.15) (type solid)) (fill none) (layer "B.Fab"))
    (pad "1" smd roundrect (at -0.484 0 270) (size 0.59 0.64) (layers "B.Cu" "B.Paste" "B.Mask") (roundrect_rratio 0.25)
      (net 77 "VDDQ") (pintype "passive"))
    (pad "2" smd roundrect (at 0.484 0 270) (size 0.59 0.64) (layers "B.Cu" "B.Paste" "B.Mask") (roundrect_rratio 0.25)
      (net 9 "GND") (pintype "passive"))
  )
	(footprint "data-center-rdimm-ddr4-tester-footprints:C_0402_1005Metric" (layer "B.Cu")
    (at 173.536328 57.710008 180)
    (descr "Capacitor SMD 0402")
    (tags "capacitor SMD 0402")
    (property "Author" "Antmicro")
    (property "Dielectric" "X5R")
    (property "License" "Apache-2.0")
    (property "MPN" "GRM155R61H104KE14D")
    (property "Manufacturer" "Murata")
    (property "Sheetfile" "DDR4.kicad_sch")
    (property "Sheetname" "DDR4")
    (property "Val" "100n")
    (property "Voltage" "50V")
    (property "ki_description" " ")
    (attr smd)
    (fp_text reference "C181" (at 0.846328 -0.329992) (layer "B.SilkS")
        (effects (font (size 0.7 0.7) (thickness 0.15)) (justify left bottom mirror))
    )
    (fp_text value "C_100n_0402" (at 0 -1.4) (layer "B.Fab") hide
        (effects (font (size 0.7 0.7) (thickness 0.15)) (justify left bottom mirror))
    )
    (fp_text user "Author: Antmicro" (at -0.932 -4.17) (layer "B.Fab") hide
        (effects (font (size 0.7 0.7) (thickness 0.15)) (justify left bottom mirror))
    )
    (fp_text user "${REFERENCE}" (at -0.932 -3.168) (layer "B.Fab") hide
        (effects (font (size 0.7 0.7) (thickness 0.15)) (justify left bottom mirror))
    )
    (fp_text user "License: Apache-2.0" (at -0.932 -5.17) (layer "B.Fab") hide
        (effects (font (size 0.7 0.7) (thickness 0.15)) (justify left bottom mirror))
    )
    (fp_rect (start -0.94 0.47) (end 0.94 -0.47)
      (stroke (width 0.05) (type solid)) (fill none) (layer "B.CrtYd"))
    (fp_rect (start -0.499 0.249) (end 0.499 -0.249)
      (stroke (width 0.15) (type solid)) (fill none) (layer "B.Fab"))
    (pad "1" smd roundrect (at -0.484 0 180) (size 0.59 0.64) (layers "B.Cu" "B.Paste" "B.Mask") (roundrect_rratio 0.25)
      (net 77 "VDDQ") (pintype "passive"))
    (pad "2" smd roundrect (at 0.484 0 180) (size 0.59 0.64) (layers "B.Cu" "B.Paste" "B.Mask") (roundrect_rratio 0.25)
      (net 9 "GND") (pintype "passive"))
  )
	(footprint "data-center-rdimm-ddr4-tester-footprints:C_0402_1005Metric" (layer "B.Cu")
    (at 121.636328 54.660008 90)
    (descr "Capacitor SMD 0402")
    (tags "capacitor SMD 0402")
    (property "Author" "Antmicro")
    (property "Dielectric" "X5R")
    (property "License" "Apache-2.0")
    (property "MPN" "GRM155R61H104KE14D")
    (property "Manufacturer" "Murata")
    (property "Sheetfile" "DDR4.kicad_sch")
    (property "Sheetname" "DDR4")
    (property "Val" "100n")
    (property "Voltage" "50V")
    (property "ki_description" " ")
    (attr smd)
    (fp_text reference "C199" (at 3.940008 0.393672 270) (layer "B.SilkS")
        (effects (font (size 0.7 0.7) (thickness 0.15)) (justify left bottom mirror))
    )
    (fp_text value "C_100n_0402" (at 0 -1.4 270) (layer "B.Fab") hide
        (effects (font (size 0.7 0.7) (thickness 0.15)) (justify left bottom mirror))
    )
    (fp_text user "${REFERENCE}" (at -0.932 -3.168 270) (layer "B.Fab") hide
        (effects (font (size 0.7 0.7) (thickness 0.15)) (justify left bottom mirror))
    )
    (fp_text user "Author: Antmicro" (at -0.932 -4.17 270) (layer "B.Fab") hide
        (effects (font (size 0.7 0.7) (thickness 0.15)) (justify left bottom mirror))
    )
    (fp_text user "License: Apache-2.0" (at -0.932 -5.17 270) (layer "B.Fab") hide
        (effects (font (size 0.7 0.7) (thickness 0.15)) (justify left bottom mirror))
    )
    (fp_rect (start -0.94 0.47) (end 0.94 -0.47)
      (stroke (width 0.05) (type solid)) (fill none) (layer "B.CrtYd"))
    (fp_rect (start -0.499 0.249) (end 0.499 -0.249)
      (stroke (width 0.15) (type solid)) (fill none) (layer "B.Fab"))
    (pad "1" smd roundrect (at -0.484 0 90) (size 0.59 0.64) (layers "B.Cu" "B.Paste" "B.Mask") (roundrect_rratio 0.25)
      (net 184 "VPP") (pintype "passive"))
    (pad "2" smd roundrect (at 0.484 0 90) (size 0.59 0.64) (layers "B.Cu" "B.Paste" "B.Mask") (roundrect_rratio 0.25)
      (net 9 "GND") (pintype "passive"))
  )
	(footprint "data-center-rdimm-ddr4-tester-footprints:C_0402_1005Metric" (layer "B.Cu")
    (at 120.626328 54.660008 90)
    (descr "Capacitor SMD 0402")
    (tags "capacitor SMD 0402")
    (property "Author" "Antmicro")
    (property "Dielectric" "X5R")
    (property "License" "Apache-2.0")
    (property "MPN" "GRM155R61H104KE14D")
    (property "Manufacturer" "Murata")
    (property "Sheetfile" "DDR4.kicad_sch")
    (property "Sheetname" "DDR4")
    (property "Val" "100n")
    (property "Voltage" "50V")
    (property "ki_description" " ")
    (attr smd)
    (fp_text reference "C200" (at 3.940008 0.393672 270) (layer "B.SilkS")
        (effects (font (size 0.7 0.7) (thickness 0.15)) (justify left bottom mirror))
    )
    (fp_text value "C_100n_0402" (at 0 -1.4 270) (layer "B.Fab") hide
        (effects (font (size 0.7 0.7) (thickness 0.15)) (justify left bottom mirror))
    )
    (fp_text user "${REFERENCE}" (at -0.932 -3.168 270) (layer "B.Fab") hide
        (effects (font (size 0.7 0.7) (thickness 0.15)) (justify left bottom mirror))
    )
    (fp_text user "Author: Antmicro" (at -0.932 -4.17 270) (layer "B.Fab") hide
        (effects (font (size 0.7 0.7) (thickness 0.15)) (justify left bottom mirror))
    )
    (fp_text user "License: Apache-2.0" (at -0.932 -5.17 270) (layer "B.Fab") hide
        (effects (font (size 0.7 0.7) (thickness 0.15)) (justify left bottom mirror))
    )
    (fp_rect (start -0.94 0.47) (end 0.94 -0.47)
      (stroke (width 0.05) (type solid)) (fill none) (layer "B.CrtYd"))
    (fp_rect (start -0.499 0.249) (end 0.499 -0.249)
      (stroke (width 0.15) (type solid)) (fill none) (layer "B.Fab"))
    (pad "1" smd roundrect (at -0.484 0 90) (size 0.59 0.64) (layers "B.Cu" "B.Paste" "B.Mask") (roundrect_rratio 0.25)
      (net 184 "VPP") (pintype "passive"))
    (pad "2" smd roundrect (at 0.484 0 90) (size 0.59 0.64) (layers "B.Cu" "B.Paste" "B.Mask") (roundrect_rratio 0.25)
      (net 9 "GND") (pintype "passive"))
  )
	(footprint "data-center-rdimm-ddr4-tester-footprints:C_0402_1005Metric" (layer "B.Cu")
    (at 119.756328 59.750008 -90)
    (descr "Capacitor SMD 0402")
    (tags "capacitor SMD 0402")
    (property "Author" "Antmicro")
    (property "Dielectric" "X5R")
    (property "License" "Apache-2.0")
    (property "MPN" "GRM155R61H104KE14D")
    (property "Manufacturer" "Murata")
    (property "Sheetfile" "DDR4.kicad_sch")
    (property "Sheetname" "DDR4")
    (property "Val" "100n")
    (property "Voltage" "50V")
    (property "ki_description" " ")
    (attr smd)
    (fp_text reference "C201" (at 0.799992 -0.353672 90) (layer "B.SilkS")
        (effects (font (size 0.7 0.7) (thickness 0.15)) (justify left bottom mirror))
    )
    (fp_text value "C_100n_0402" (at 0 -1.4 90) (layer "B.Fab") hide
        (effects (font (size 0.7 0.7) (thickness 0.15)) (justify left bottom mirror))
    )
    (fp_text user "${REFERENCE}" (at -0.932 -3.168 90) (layer "B.Fab") hide
        (effects (font (size 0.7 0.7) (thickness 0.15)) (justify left bottom mirror))
    )
    (fp_text user "Author: Antmicro" (at -0.932 -4.17 90) (layer "B.Fab") hide
        (effects (font (size 0.7 0.7) (thickness 0.15)) (justify left bottom mirror))
    )
    (fp_text user "License: Apache-2.0" (at -0.932 -5.17 90) (layer "B.Fab") hide
        (effects (font (size 0.7 0.7) (thickness 0.15)) (justify left bottom mirror))
    )
    (fp_rect (start -0.94 0.47) (end 0.94 -0.47)
      (stroke (width 0.05) (type solid)) (fill none) (layer "B.CrtYd"))
    (fp_rect (start -0.499 0.249) (end 0.499 -0.249)
      (stroke (width 0.15) (type solid)) (fill none) (layer "B.Fab"))
    (pad "1" smd roundrect (at -0.484 0 270) (size 0.59 0.64) (layers "B.Cu" "B.Paste" "B.Mask") (roundrect_rratio 0.25)
      (net 184 "VPP") (pintype "passive"))
    (pad "2" smd roundrect (at 0.484 0 270) (size 0.59 0.64) (layers "B.Cu" "B.Paste" "B.Mask") (roundrect_rratio 0.25)
      (net 9 "GND") (pintype "passive"))
  )
	(footprint "data-center-rdimm-ddr4-tester-footprints:C_0402_1005Metric" (layer "B.Cu")
    (at 120.736328 59.760008 -90)
    (descr "Capacitor SMD 0402")
    (tags "capacitor SMD 0402")
    (property "Author" "Antmicro")
    (property "Dielectric" "X5R")
    (property "License" "Apache-2.0")
    (property "MPN" "GRM155R61H104KE14D")
    (property "Manufacturer" "Murata")
    (property "Sheetfile" "DDR4.kicad_sch")
    (property "Sheetname" "DDR4")
    (property "Val" "100n")
    (property "Voltage" "50V")
    (property "ki_description" " ")
    (attr smd)
    (fp_text reference "C202" (at 0.799992 -0.353672 90) (layer "B.SilkS")
        (effects (font (size 0.7 0.7) (thickness 0.15)) (justify left bottom mirror))
    )
    (fp_text value "C_100n_0402" (at 0 -1.4 90) (layer "B.Fab") hide
        (effects (font (size 0.7 0.7) (thickness 0.15)) (justify left bottom mirror))
    )
    (fp_text user "Author: Antmicro" (at -0.932 -4.17 90) (layer "B.Fab") hide
        (effects (font (size 0.7 0.7) (thickness 0.15)) (justify left bottom mirror))
    )
    (fp_text user "License: Apache-2.0" (at -0.932 -5.17 90) (layer "B.Fab") hide
        (effects (font (size 0.7 0.7) (thickness 0.15)) (justify left bottom mirror))
    )
    (fp_text user "${REFERENCE}" (at -0.932 -3.168 90) (layer "B.Fab") hide
        (effects (font (size 0.7 0.7) (thickness 0.15)) (justify left bottom mirror))
    )
    (fp_rect (start -0.94 0.47) (end 0.94 -0.47)
      (stroke (width 0.05) (type solid)) (fill none) (layer "B.CrtYd"))
    (fp_rect (start -0.499 0.249) (end 0.499 -0.249)
      (stroke (width 0.15) (type solid)) (fill none) (layer "B.Fab"))
    (pad "1" smd roundrect (at -0.484 0 270) (size 0.59 0.64) (layers "B.Cu" "B.Paste" "B.Mask") (roundrect_rratio 0.25)
      (net 184 "VPP") (pintype "passive"))
    (pad "2" smd roundrect (at 0.484 0 270) (size 0.59 0.64) (layers "B.Cu" "B.Paste" "B.Mask") (roundrect_rratio 0.25)
      (net 9 "GND") (pintype "passive"))
  )
	(footprint "data-center-rdimm-ddr4-tester-footprints:C_0402_1005Metric" (layer "B.Cu")
    (at 121.736328 59.760008 -90)
    (descr "Capacitor SMD 0402")
    (tags "capacitor SMD 0402")
    (property "Author" "Antmicro")
    (property "Dielectric" "X5R")
    (property "License" "Apache-2.0")
    (property "MPN" "GRM155R61H104KE14D")
    (property "Manufacturer" "Murata")
    (property "Sheetfile" "DDR4.kicad_sch")
    (property "Sheetname" "DDR4")
    (property "Val" "100n")
    (property "Voltage" "50V")
    (property "ki_description" " ")
    (attr smd)
    (fp_text reference "C203" (at 0.799992 -0.353672 90) (layer "B.SilkS")
        (effects (font (size 0.7 0.7) (thickness 0.15)) (justify left bottom mirror))
    )
    (fp_text value "C_100n_0402" (at 0 -1.4 90) (layer "B.Fab") hide
        (effects (font (size 0.7 0.7) (thickness 0.15)) (justify left bottom mirror))
    )
    (fp_text user "${REFERENCE}" (at -0.932 -3.168 90) (layer "B.Fab") hide
        (effects (font (size 0.7 0.7) (thickness 0.15)) (justify left bottom mirror))
    )
    (fp_text user "License: Apache-2.0" (at -0.932 -5.17 90) (layer "B.Fab") hide
        (effects (font (size 0.7 0.7) (thickness 0.15)) (justify left bottom mirror))
    )
    (fp_text user "Author: Antmicro" (at -0.932 -4.17 90) (layer "B.Fab") hide
        (effects (font (size 0.7 0.7) (thickness 0.15)) (justify left bottom mirror))
    )
    (fp_rect (start -0.94 0.47) (end 0.94 -0.47)
      (stroke (width 0.05) (type solid)) (fill none) (layer "B.CrtYd"))
    (fp_rect (start -0.499 0.249) (end 0.499 -0.249)
      (stroke (width 0.15) (type solid)) (fill none) (layer "B.Fab"))
    (pad "1" smd roundrect (at -0.484 0 270) (size 0.59 0.64) (layers "B.Cu" "B.Paste" "B.Mask") (roundrect_rratio 0.25)
      (net 184 "VPP") (pintype "passive"))
    (pad "2" smd roundrect (at 0.484 0 270) (size 0.59 0.64) (layers "B.Cu" "B.Paste" "B.Mask") (roundrect_rratio 0.25)
      (net 9 "GND") (pintype "passive"))
  )
	(footprint "data-center-rdimm-ddr4-tester-footprints:C_0402_1005Metric" (layer "B.Cu")
    (at 181.796328 54.090008 90)
    (descr "Capacitor SMD 0402")
    (tags "capacitor SMD 0402")
    (property "Author" "Antmicro")
    (property "Dielectric" "X5R")
    (property "License" "Apache-2.0")
    (property "MPN" "GRM155R61H104KE14D")
    (property "Manufacturer" "Murata")
    (property "Sheetfile" "DDR4.kicad_sch")
    (property "Sheetname" "DDR4")
    (property "Val" "100n")
    (property "Voltage" "50V")
    (property "ki_description" " ")
    (attr smd)
    (fp_text reference "C204" (at 4.060008 0.483672 270) (layer "B.SilkS")
        (effects (font (size 0.7 0.7) (thickness 0.15)) (justify left bottom mirror))
    )
    (fp_text value "C_100n_0402" (at 0 -1.4 270) (layer "B.Fab") hide
        (effects (font (size 0.7 0.7) (thickness 0.15)) (justify left bottom mirror))
    )
    (fp_text user "License: Apache-2.0" (at -0.932 -5.17 270) (layer "B.Fab") hide
        (effects (font (size 0.7 0.7) (thickness 0.15)) (justify left bottom mirror))
    )
    (fp_text user "Author: Antmicro" (at -0.932 -4.17 270) (layer "B.Fab") hide
        (effects (font (size 0.7 0.7) (thickness 0.15)) (justify left bottom mirror))
    )
    (fp_text user "${REFERENCE}" (at -0.932 -3.168 270) (layer "B.Fab") hide
        (effects (font (size 0.7 0.7) (thickness 0.15)) (justify left bottom mirror))
    )
    (fp_rect (start -0.94 0.47) (end 0.94 -0.47)
      (stroke (width 0.05) (type solid)) (fill none) (layer "B.CrtYd"))
    (fp_rect (start -0.499 0.249) (end 0.499 -0.249)
      (stroke (width 0.15) (type solid)) (fill none) (layer "B.Fab"))
    (pad "1" smd roundrect (at -0.484 0 90) (size 0.59 0.64) (layers "B.Cu" "B.Paste" "B.Mask") (roundrect_rratio 0.25)
      (net 186 "VTT") (pintype "passive"))
    (pad "2" smd roundrect (at 0.484 0 90) (size 0.59 0.64) (layers "B.Cu" "B.Paste" "B.Mask") (roundrect_rratio 0.25)
      (net 9 "GND") (pintype "passive"))
  )
	(footprint "data-center-rdimm-ddr4-tester-footprints:C_0402_1005Metric" (layer "B.Cu")
    (at 181.636328 60.670008 -90)
    (descr "Capacitor SMD 0402")
    (tags "capacitor SMD 0402")
    (property "Author" "Antmicro")
    (property "Dielectric" "X5R")
    (property "License" "Apache-2.0")
    (property "MPN" "GRM155R61H104KE14D")
    (property "Manufacturer" "Murata")
    (property "Sheetfile" "DDR4.kicad_sch")
    (property "Sheetname" "DDR4")
    (property "Val" "100n")
    (property "Voltage" "50V")
    (property "ki_description" " ")
    (attr smd)
    (fp_text reference "C205" (at 0.739992 -0.363672 90) (layer "B.SilkS")
        (effects (font (size 0.7 0.7) (thickness 0.15)) (justify left bottom mirror))
    )
    (fp_text value "C_100n_0402" (at 0 -1.4 90) (layer "B.Fab") hide
        (effects (font (size 0.7 0.7) (thickness 0.15)) (justify left bottom mirror))
    )
    (fp_text user "License: Apache-2.0" (at -0.932 -5.17 90) (layer "B.Fab") hide
        (effects (font (size 0.7 0.7) (thickness 0.15)) (justify left bottom mirror))
    )
    (fp_text user "Author: Antmicro" (at -0.932 -4.17 90) (layer "B.Fab") hide
        (effects (font (size 0.7 0.7) (thickness 0.15)) (justify left bottom mirror))
    )
    (fp_text user "${REFERENCE}" (at -0.932 -3.168 90) (layer "B.Fab") hide
        (effects (font (size 0.7 0.7) (thickness 0.15)) (justify left bottom mirror))
    )
    (fp_rect (start -0.94 0.47) (end 0.94 -0.47)
      (stroke (width 0.05) (type solid)) (fill none) (layer "B.CrtYd"))
    (fp_rect (start -0.499 0.249) (end 0.499 -0.249)
      (stroke (width 0.15) (type solid)) (fill none) (layer "B.Fab"))
    (pad "1" smd roundrect (at -0.484 0 270) (size 0.59 0.64) (layers "B.Cu" "B.Paste" "B.Mask") (roundrect_rratio 0.25)
      (net 186 "VTT") (pintype "passive"))
    (pad "2" smd roundrect (at 0.484 0 270) (size 0.59 0.64) (layers "B.Cu" "B.Paste" "B.Mask") (roundrect_rratio 0.25)
      (net 9 "GND") (pintype "passive"))
  )
	(footprint "data-center-rdimm-ddr4-tester-footprints:C_0402_1005Metric" (layer "B.Cu")
    (at 168.436328 57.660008)
    (descr "Capacitor SMD 0402")
    (tags "capacitor SMD 0402")
    (property "Author" "Antmicro")
    (property "Dielectric" "X5R")
    (property "License" "Apache-2.0")
    (property "MPN" "GRM155R61H104KE14D")
    (property "Manufacturer" "Murata")
    (property "Sheetfile" "DDR4.kicad_sch")
    (property "Sheetname" "DDR4")
    (property "Val" "100n")
    (property "Voltage" "50V")
    (property "ki_description" " ")
    (attr smd)
    (fp_text reference "C176" (at 1.063672 1.189992 180) (layer "B.SilkS")
        (effects (font (size 0.7 0.7) (thickness 0.15)) (justify left bottom mirror))
    )
    (fp_text value "C_100n_0402" (at 0 -1.4 180) (layer "B.Fab") hide
        (effects (font (size 0.7 0.7) (thickness 0.15)) (justify left bottom mirror))
    )
    (fp_text user "${REFERENCE}" (at -0.932 -3.168 180) (layer "B.Fab") hide
        (effects (font (size 0.7 0.7) (thickness 0.15)) (justify left bottom mirror))
    )
    (fp_text user "License: Apache-2.0" (at -0.932 -5.17 180) (layer "B.Fab") hide
        (effects (font (size 0.7 0.7) (thickness 0.15)) (justify left bottom mirror))
    )
    (fp_text user "Author: Antmicro" (at -0.932 -4.17 180) (layer "B.Fab") hide
        (effects (font (size 0.7 0.7) (thickness 0.15)) (justify left bottom mirror))
    )
    (fp_rect (start -0.94 0.47) (end 0.94 -0.47)
      (stroke (width 0.05) (type solid)) (fill none) (layer "B.CrtYd"))
    (fp_rect (start -0.499 0.249) (end 0.499 -0.249)
      (stroke (width 0.15) (type solid)) (fill none) (layer "B.Fab"))
    (pad "1" smd roundrect (at -0.484 0) (size 0.59 0.64) (layers "B.Cu" "B.Paste" "B.Mask") (roundrect_rratio 0.25)
      (net 77 "VDDQ") (pintype "passive"))
    (pad "2" smd roundrect (at 0.484 0) (size 0.59 0.64) (layers "B.Cu" "B.Paste" "B.Mask") (roundrect_rratio 0.25)
      (net 9 "GND") (pintype "passive"))
  )
)
